(kicad_pcb
	(version 20260206)
	(generator "pcbnew")
	(generator_version "10.0")
	(general
		(thickness 1.6)
		(legacy_teardrops no)
	)
	(paper "A4")
	(title_block
		(title "01162023_DA0F0TEBIF0_F0T_Expander_BD_F_brd_V02_OCP.brd")
		(comment 1 "Grand Teton / footprints 4274-4280 of 9728")
	)
	(layers
		(0 "F.Cu" signal "TOP")
		(4 "In1.Cu" signal "GND")
		(6 "In2.Cu" signal "VCC")
		(8 "In3.Cu" signal "VCC1")
		(10 "In4.Cu" signal "GND1")
		(12 "In5.Cu" signal "IN1")
		(14 "In6.Cu" signal "GND2")
		(16 "In7.Cu" signal "IN2")
		(18 "In8.Cu" signal "GND3")
		(20 "In9.Cu" signal "IN3")
		(22 "In10.Cu" signal "GND4")
		(24 "In11.Cu" signal "IN4")
		(26 "In12.Cu" signal "GND5")
		(28 "In13.Cu" signal "IN5")
		(30 "In14.Cu" signal "GND6")
		(32 "In15.Cu" signal "IN6")
		(34 "In16.Cu" signal "GND7")
		(2 "B.Cu" signal "BOTTOM")
		(9 "F.Adhes" user "F.Adhesive")
		(11 "B.Adhes" user "B.Adhesive")
		(13 "F.Paste" user "Package Geometry/Pastemask Top")
		(15 "B.Paste" user "Package Geometry/Pastemask Bottom")
		(5 "F.SilkS" user "Ref Des/Silkscreen Top")
		(7 "B.SilkS" user "Ref Des/Silkscreen Bottom")
		(1 "F.Mask" user "Board Geometry/Soldermask Top")
		(3 "B.Mask" user "Board Geometry/Soldermask Bottom")
		(17 "Dwgs.User" user "User.Drawings")
		(19 "Cmts.User" user "User.Comments")
		(21 "Eco1.User" user "User.Eco1")
		(23 "Eco2.User" user "User.Eco2")
		(25 "Edge.Cuts" user "Board Geometry/Outline")
		(27 "Margin" user)
		(31 "F.CrtYd" user "Package Geometry/Place Bound Top")
		(29 "B.CrtYd" user "Package Geometry/Place Bound Bottom")
		(35 "F.Fab" user "Ref Des/Assembly Top")
		(33 "B.Fab" user "Ref Des/Assembly Bottom")
	)
	(footprint ""
		(layer "F.Cu")
		(at 187.032392 -356.22103 90)
		(property "Reference" "C376"
			(at 0 0 90)
			(layer "F.SilkS")
			(hide yes)
			(effects
				(font
					(size 1.27 1.27)
				)
			)
		)
		(property "Value" ""
			(at 0 0 90)
			(layer "F.Fab")
			(effects
				(font
					(size 1.27 1.27)
				)
			)
		)
		(duplicate_pad_numbers_are_jumpers no)
		(fp_line
			(start 0.299974 -0.150114)
			(end 0.299974 0.150114)
			(stroke
				(width 0.1)
				(type default)
			)
			(layer "F.Fab")
		)
		(fp_line
			(start -0.299974 -0.150114)
			(end 0.299974 -0.150114)
			(stroke
				(width 0.1)
				(type default)
			)
			(layer "F.Fab")
		)
		(fp_line
			(start 0.299974 0.150114)
			(end -0.299974 0.150114)
			(stroke
				(width 0.1)
				(type default)
			)
			(layer "F.Fab")
		)
		(fp_line
			(start -0.299974 0.150114)
			(end -0.299974 -0.150114)
			(stroke
				(width 0.1)
				(type default)
			)
			(layer "F.Fab")
		)
		(pad "1" smd rect
			(at -0.2667 0 90)
			(size 0.3048 0.381)
			(layers "F.Cu" "F.Mask" "F.Paste")
			(net "P5E_PEX1_STN7_TX_DP<125>")
		)
		(pad "2" smd rect
			(at 0.2667 0 90)
			(size 0.3048 0.381)
			(layers "F.Cu" "F.Mask" "F.Paste")
			(net "P5E_PEX1_STN7_TX_C_DP<125>")
		)
	)
	(footprint ""
		(layer "F.Cu")
		(at 310.443626 -49.95291 180)
		(property "Reference" "R5901"
			(at 0 0 180)
			(layer "F.SilkS")
			(hide yes)
			(effects
				(font
					(size 1.27 1.27)
				)
			)
		)
		(property "Value" ""
			(at 0 0 180)
			(layer "F.Fab")
			(effects
				(font
					(size 1.27 1.27)
				)
			)
		)
		(duplicate_pad_numbers_are_jumpers no)
		(fp_line
			(start 0.7874 0.4064)
			(end -0.7874 0.4064)
			(stroke
				(width 0.1524)
				(type default)
			)
			(layer "F.SilkS")
		)
		(fp_line
			(start 0.7874 -0.4064)
			(end 0.7874 0.4064)
			(stroke
				(width 0.1524)
				(type default)
			)
			(layer "F.SilkS")
		)
		(fp_line
			(start -0.7874 0.4064)
			(end -0.7874 -0.4064)
			(stroke
				(width 0.1524)
				(type default)
			)
			(layer "F.SilkS")
		)
		(fp_line
			(start -0.7874 -0.4064)
			(end 0.7874 -0.4064)
			(stroke
				(width 0.1524)
				(type default)
			)
			(layer "F.SilkS")
		)
		(fp_line
			(start 0.67945 0.3048)
			(end 0.120396 0.3048)
			(stroke
				(width 0.1)
				(type default)
			)
			(layer "F.Fab")
		)
		(fp_line
			(start 0.67945 -0.3048)
			(end 0.67945 0.3048)
			(stroke
				(width 0.1)
				(type default)
			)
			(layer "F.Fab")
		)
		(fp_line
			(start 0.12065 -0.2794)
			(end 0.12065 -0.3048)
			(stroke
				(width 0.1)
				(type default)
			)
			(layer "F.Fab")
		)
		(fp_line
			(start 0.12065 -0.3048)
			(end 0.67945 -0.3048)
			(stroke
				(width 0.1)
				(type default)
			)
			(layer "F.Fab")
		)
		(fp_line
			(start 0.120396 0.3048)
			(end 0.120396 0.2794)
			(stroke
				(width 0.1)
				(type default)
			)
			(layer "F.Fab")
		)
		(fp_line
			(start 0.120396 0.2794)
			(end -0.12065 0.2794)
			(stroke
				(width 0.1)
				(type default)
			)
			(layer "F.Fab")
		)
		(fp_line
			(start -0.12065 0.3048)
			(end -0.67945 0.3048)
			(stroke
				(width 0.1)
				(type default)
			)
			(layer "F.Fab")
		)
		(fp_line
			(start -0.12065 0.2794)
			(end -0.12065 0.3048)
			(stroke
				(width 0.1)
				(type default)
			)
			(layer "F.Fab")
		)
		(fp_line
			(start -0.12065 -0.2794)
			(end 0.12065 -0.2794)
			(stroke
				(width 0.1)
				(type default)
			)
			(layer "F.Fab")
		)
		(fp_line
			(start -0.12065 -0.305054)
			(end -0.12065 -0.2794)
			(stroke
				(width 0.1)
				(type default)
			)
			(layer "F.Fab")
		)
		(fp_line
			(start -0.67945 0.3048)
			(end -0.67945 -0.305054)
			(stroke
				(width 0.1)
				(type default)
			)
			(layer "F.Fab")
		)
		(fp_line
			(start -0.67945 -0.305054)
			(end -0.12065 -0.305054)
			(stroke
				(width 0.1)
				(type default)
			)
			(layer "F.Fab")
		)
		(pad "1" smd circle
			(at -0.40005 0 180)
			(size 0 0)
			(layers "F.Cu" "F.Mask" "F.Paste")
			(net "SSD10_ADC_A0")
		)
		(pad "2" smd circle
			(at 0.40005 0 180)
			(size 0 0)
			(layers "F.Cu" "F.Mask" "F.Paste")
			(net "SMB_SSD10_ADC_SDA")
		)
	)
	(footprint ""
		(layer "F.Cu")
		(at 326.187816 -45.704252 90)
		(property "Reference" "R626"
			(at 0 0 90)
			(layer "F.SilkS")
			(hide yes)
			(effects
				(font
					(size 1.27 1.27)
				)
			)
		)
		(property "Value" ""
			(at 0 0 90)
			(layer "F.Fab")
			(effects
				(font
					(size 1.27 1.27)
				)
			)
		)
		(duplicate_pad_numbers_are_jumpers no)
		(fp_line
			(start 3.937508 -1.8796)
			(end -3.937508 -1.8796)
			(stroke
				(width 0.1524)
				(type default)
			)
			(layer "F.SilkS")
		)
		(fp_line
			(start -3.937508 -1.8796)
			(end -3.937508 1.8796)
			(stroke
				(width 0.1524)
				(type default)
			)
			(layer "F.SilkS")
		)
		(fp_line
			(start 3.937508 1.8796)
			(end 3.937508 -1.8796)
			(stroke
				(width 0.1524)
				(type default)
			)
			(layer "F.SilkS")
		)
		(fp_line
			(start -3.937508 1.8796)
			(end 3.937508 1.8796)
			(stroke
				(width 0.1524)
				(type default)
			)
			(layer "F.SilkS")
		)
		(fp_line
			(start 3.275076 -1.674876)
			(end -3.275076 -1.674876)
			(stroke
				(width 0.1)
				(type default)
			)
			(layer "F.Fab")
		)
		(fp_line
			(start -3.275076 -1.674876)
			(end -3.275076 1.674876)
			(stroke
				(width 0.1)
				(type default)
			)
			(layer "F.Fab")
		)
		(fp_line
			(start 3.275076 1.674876)
			(end 3.275076 -1.674876)
			(stroke
				(width 0.1)
				(type default)
			)
			(layer "F.Fab")
		)
		(fp_line
			(start -3.275076 1.674876)
			(end 3.275076 1.674876)
			(stroke
				(width 0.1)
				(type default)
			)
			(layer "F.Fab")
		)
		(pad "1" smd rect
			(at -2.350008 0 90)
			(size 2.921 3.5052)
			(layers "F.Cu" "F.Mask" "F.Paste")
			(net "P12V_SSD11")
		)
		(pad "2" smd rect
			(at 2.350008 0 90)
			(size 2.921 3.5052)
			(layers "F.Cu" "F.Mask" "F.Paste")
			(net "P12V_SSD11_R")
		)
	)
	(footprint ""
		(layer "F.Cu")
		(at 339.344 -236.855 90)
		(property "Reference" "R1792"
			(at 0 0 90)
			(layer "F.SilkS")
			(hide yes)
			(effects
				(font
					(size 1.27 1.27)
				)
			)
		)
		(property "Value" ""
			(at 0 0 90)
			(layer "F.Fab")
			(effects
				(font
					(size 1.27 1.27)
				)
			)
		)
		(duplicate_pad_numbers_are_jumpers no)
		(fp_line
			(start 0.7874 -0.4064)
			(end 0.7874 0.4064)
			(stroke
				(width 0.1524)
				(type default)
			)
			(layer "F.SilkS")
		)
		(fp_line
			(start -0.7874 -0.4064)
			(end 0.7874 -0.4064)
			(stroke
				(width 0.1524)
				(type default)
			)
			(layer "F.SilkS")
		)
		(fp_line
			(start 0.7874 0.4064)
			(end -0.7874 0.4064)
			(stroke
				(width 0.1524)
				(type default)
			)
			(layer "F.SilkS")
		)
		(fp_line
			(start -0.7874 0.4064)
			(end -0.7874 -0.4064)
			(stroke
				(width 0.1524)
				(type default)
			)
			(layer "F.SilkS")
		)
		(fp_line
			(start -0.12065 -0.305054)
			(end -0.12065 -0.2794)
			(stroke
				(width 0.1)
				(type default)
			)
			(layer "F.Fab")
		)
		(fp_line
			(start -0.67945 -0.305054)
			(end -0.12065 -0.305054)
			(stroke
				(width 0.1)
				(type default)
			)
			(layer "F.Fab")
		)
		(fp_line
			(start 0.67945 -0.3048)
			(end 0.67945 0.3048)
			(stroke
				(width 0.1)
				(type default)
			)
			(layer "F.Fab")
		)
		(fp_line
			(start 0.12065 -0.3048)
			(end 0.67945 -0.3048)
			(stroke
				(width 0.1)
				(type default)
			)
			(layer "F.Fab")
		)
		(fp_line
			(start 0.12065 -0.2794)
			(end 0.12065 -0.3048)
			(stroke
				(width 0.1)
				(type default)
			)
			(layer "F.Fab")
		)
		(fp_line
			(start -0.12065 -0.2794)
			(end 0.12065 -0.2794)
			(stroke
				(width 0.1)
				(type default)
			)
			(layer "F.Fab")
		)
		(fp_line
			(start 0.120396 0.2794)
			(end -0.12065 0.2794)
			(stroke
				(width 0.1)
				(type default)
			)
			(layer "F.Fab")
		)
		(fp_line
			(start -0.12065 0.2794)
			(end -0.12065 0.3048)
			(stroke
				(width 0.1)
				(type default)
			)
			(layer "F.Fab")
		)
		(fp_line
			(start 0.67945 0.3048)
			(end 0.120396 0.3048)
			(stroke
				(width 0.1)
				(type default)
			)
			(layer "F.Fab")
		)
		(fp_line
			(start 0.120396 0.3048)
			(end 0.120396 0.2794)
			(stroke
				(width 0.1)
				(type default)
			)
			(layer "F.Fab")
		)
		(fp_line
			(start -0.12065 0.3048)
			(end -0.67945 0.3048)
			(stroke
				(width 0.1)
				(type default)
			)
			(layer "F.Fab")
		)
		(fp_line
			(start -0.67945 0.3048)
			(end -0.67945 -0.305054)
			(stroke
				(width 0.1)
				(type default)
			)
			(layer "F.Fab")
		)
		(pad "1" smd circle
			(at -0.40005 0 90)
			(size 0 0)
			(layers "F.Cu" "F.Mask" "F.Paste")
			(net "P3V3_AUX")
		)
		(pad "2" smd circle
			(at 0.40005 0 90)
			(size 0 0)
			(layers "F.Cu" "F.Mask" "F.Paste")
			(net "RST_MB_PERST_2_ISO_R_N")
		)
	)
	(footprint ""
		(layer "F.Cu")
		(at 355.913436 -139.376404)
		(property "Reference" "R858"
			(at 0 0 0)
			(layer "F.SilkS")
			(hide yes)
			(effects
				(font
					(size 1.27 1.27)
				)
			)
		)
		(property "Value" ""
			(at 0 0 0)
			(layer "F.Fab")
			(effects
				(font
					(size 1.27 1.27)
				)
			)
		)
		(duplicate_pad_numbers_are_jumpers no)
		(fp_line
			(start -0.7874 -0.4064)
			(end 0.7874 -0.4064)
			(stroke
				(width 0.1524)
				(type default)
			)
			(layer "F.SilkS")
		)
		(fp_line
			(start -0.7874 0.4064)
			(end -0.7874 -0.4064)
			(stroke
				(width 0.1524)
				(type default)
			)
			(layer "F.SilkS")
		)
		(fp_line
			(start 0.7874 -0.4064)
			(end 0.7874 0.4064)
			(stroke
				(width 0.1524)
				(type default)
			)
			(layer "F.SilkS")
		)
		(fp_line
			(start 0.7874 0.4064)
			(end -0.7874 0.4064)
			(stroke
				(width 0.1524)
				(type default)
			)
			(layer "F.SilkS")
		)
		(fp_line
			(start -0.67945 -0.305054)
			(end -0.12065 -0.305054)
			(stroke
				(width 0.1)
				(type default)
			)
			(layer "F.Fab")
		)
		(fp_line
			(start -0.67945 0.3048)
			(end -0.67945 -0.305054)
			(stroke
				(width 0.1)
				(type default)
			)
			(layer "F.Fab")
		)
		(fp_line
			(start -0.12065 -0.305054)
			(end -0.12065 -0.2794)
			(stroke
				(width 0.1)
				(type default)
			)
			(layer "F.Fab")
		)
		(fp_line
			(start -0.12065 -0.2794)
			(end 0.12065 -0.2794)
			(stroke
				(width 0.1)
				(type default)
			)
			(layer "F.Fab")
		)
		(fp_line
			(start -0.12065 0.2794)
			(end -0.12065 0.3048)
			(stroke
				(width 0.1)
				(type default)
			)
			(layer "F.Fab")
		)
		(fp_line
			(start -0.12065 0.3048)
			(end -0.67945 0.3048)
			(stroke
				(width 0.1)
				(type default)
			)
			(layer "F.Fab")
		)
		(fp_line
			(start 0.120396 0.2794)
			(end -0.12065 0.2794)
			(stroke
				(width 0.1)
				(type default)
			)
			(layer "F.Fab")
		)
		(fp_line
			(start 0.120396 0.3048)
			(end 0.120396 0.2794)
			(stroke
				(width 0.1)
				(type default)
			)
			(layer "F.Fab")
		)
		(fp_line
			(start 0.12065 -0.3048)
			(end 0.67945 -0.3048)
			(stroke
				(width 0.1)
				(type default)
			)
			(layer "F.Fab")
		)
		(fp_line
			(start 0.12065 -0.2794)
			(end 0.12065 -0.3048)
			(stroke
				(width 0.1)
				(type default)
			)
			(layer "F.Fab")
		)
		(fp_line
			(start 0.67945 -0.3048)
			(end 0.67945 0.3048)
			(stroke
				(width 0.1)
				(type default)
			)
			(layer "F.Fab")
		)
		(fp_line
			(start 0.67945 0.3048)
			(end 0.120396 0.3048)
			(stroke
				(width 0.1)
				(type default)
			)
			(layer "F.Fab")
		)
		(pad "1" smd circle
			(at -0.40005 0)
			(size 0 0)
			(layers "F.Cu" "F.Mask" "F.Paste")
			(net "P3V3_AUX")
		)
		(pad "2" smd circle
			(at 0.40005 0)
			(size 0 0)
			(layers "F.Cu" "F.Mask" "F.Paste")
			(net "PWRGD_P12V_NIC6")
		)
	)
	(footprint ""
		(layer "F.Cu")
		(at 340.561422 -196.51345)
		(property "Reference" "R4236"
			(at 0 0 0)
			(layer "F.SilkS")
			(hide yes)
			(effects
				(font
					(size 1.27 1.27)
				)
			)
		)
		(property "Value" ""
			(at 0 0 0)
			(layer "F.Fab")
			(effects
				(font
					(size 1.27 1.27)
				)
			)
		)
		(duplicate_pad_numbers_are_jumpers no)
		(fp_line
			(start -0.7874 -0.4064)
			(end 0.7874 -0.4064)
			(stroke
				(width 0.1524)
				(type default)
			)
			(layer "F.SilkS")
		)
		(fp_line
			(start -0.7874 0.4064)
			(end -0.7874 -0.4064)
			(stroke
				(width 0.1524)
				(type default)
			)
			(layer "F.SilkS")
		)
		(fp_line
			(start 0.7874 -0.4064)
			(end 0.7874 0.4064)
			(stroke
				(width 0.1524)
				(type default)
			)
			(layer "F.SilkS")
		)
		(fp_line
			(start 0.7874 0.4064)
			(end -0.7874 0.4064)
			(stroke
				(width 0.1524)
				(type default)
			)
			(layer "F.SilkS")
		)
		(fp_line
			(start -0.67945 -0.305054)
			(end -0.12065 -0.305054)
			(stroke
				(width 0.1)
				(type default)
			)
			(layer "F.Fab")
		)
		(fp_line
			(start -0.67945 0.3048)
			(end -0.67945 -0.305054)
			(stroke
				(width 0.1)
				(type default)
			)
			(layer "F.Fab")
		)
		(fp_line
			(start -0.12065 -0.305054)
			(end -0.12065 -0.2794)
			(stroke
				(width 0.1)
				(type default)
			)
			(layer "F.Fab")
		)
		(fp_line
			(start -0.12065 -0.2794)
			(end 0.12065 -0.2794)
			(stroke
				(width 0.1)
				(type default)
			)
			(layer "F.Fab")
		)
		(fp_line
			(start -0.12065 0.2794)
			(end -0.12065 0.3048)
			(stroke
				(width 0.1)
				(type default)
			)
			(layer "F.Fab")
		)
		(fp_line
			(start -0.12065 0.3048)
			(end -0.67945 0.3048)
			(stroke
				(width 0.1)
				(type default)
			)
			(layer "F.Fab")
		)
		(fp_line
			(start 0.120396 0.2794)
			(end -0.12065 0.2794)
			(stroke
				(width 0.1)
				(type default)
			)
			(layer "F.Fab")
		)
		(fp_line
			(start 0.120396 0.3048)
			(end 0.120396 0.2794)
			(stroke
				(width 0.1)
				(type default)
			)
			(layer "F.Fab")
		)
		(fp_line
			(start 0.12065 -0.3048)
			(end 0.67945 -0.3048)
			(stroke
				(width 0.1)
				(type default)
			)
			(layer "F.Fab")
		)
		(fp_line
			(start 0.12065 -0.2794)
			(end 0.12065 -0.3048)
			(stroke
				(width 0.1)
				(type default)
			)
			(layer "F.Fab")
		)
		(fp_line
			(start 0.67945 -0.3048)
			(end 0.67945 0.3048)
			(stroke
				(width 0.1)
				(type default)
			)
			(layer "F.Fab")
		)
		(fp_line
			(start 0.67945 0.3048)
			(end 0.120396 0.3048)
			(stroke
				(width 0.1)
				(type default)
			)
			(layer "F.Fab")
		)
		(pad "1" smd circle
			(at -0.40005 0)
			(size 0 0)
			(layers "F.Cu" "F.Mask" "F.Paste")
			(net "IOEXP_DBV2_A0")
		)
		(pad "2" smd circle
			(at 0.40005 0)
			(size 0 0)
			(layers "F.Cu" "F.Mask" "F.Paste")
			(net "P3V3_AUX")
		)
	)
	(footprint ""
		(layer "F.Cu")
		(at 126.63043 -144.067276 180)
		(property "Reference" "PC624"
			(at 0 0 180)
			(layer "F.SilkS")
			(hide yes)
			(effects
				(font
					(size 1.27 1.27)
				)
			)
		)
		(property "Value" ""
			(at 0 0 180)
			(layer "F.Fab")
			(effects
				(font
					(size 1.27 1.27)
				)
			)
		)
		(duplicate_pad_numbers_are_jumpers no)
		(fp_line
			(start 1.524 0.762)
			(end -1.524 0.762)
			(stroke
				(width 0.1524)
				(type default)
			)
			(layer "F.SilkS")
		)
		(fp_line
			(start 1.524 -0.762)
			(end 1.524 0.762)
			(stroke
				(width 0.1524)
				(type default)
			)
			(layer "F.SilkS")
		)
		(fp_line
			(start -1.524 0.762)
			(end -1.524 -0.762)
			(stroke
				(width 0.1524)
				(type default)
			)
			(layer "F.SilkS")
		)
		(fp_line
			(start -1.524 -0.762)
			(end 1.524 -0.762)
			(stroke
				(width 0.1524)
				(type default)
			)
			(layer "F.SilkS")
		)
		(fp_line
			(start 1.1049 0.724916)
			(end 1.1049 -0.724916)
			(stroke
				(width 0.1)
				(type default)
			)
			(layer "F.Fab")
		)
		(fp_line
			(start 1.1049 -0.724916)
			(end -1.1049 -0.724916)
			(stroke
				(width 0.1)
				(type default)
			)
			(layer "F.Fab")
		)
		(fp_line
			(start -1.1049 0.724916)
			(end 1.1049 0.724916)
			(stroke
				(width 0.1)
				(type default)
			)
			(layer "F.Fab")
		)
		(fp_line
			(start -1.1049 -0.724916)
			(end -1.1049 0.724916)
			(stroke
				(width 0.1)
				(type default)
			)
			(layer "F.Fab")
		)
		(pad "1" smd rect
			(at -0.889 0)
			(size 1.016 1.27)
			(layers "F.Cu" "F.Mask" "F.Paste")
			(net "P12V_NIC2_R")
		)
		(pad "2" smd rect
			(at 0.889 0)
			(size 1.016 1.27)
			(layers "F.Cu" "F.Mask" "F.Paste")
			(net "GND")
		)
	)
)
